(kicad_pcb
	(version 20241229)
	(generator "pcbnew")
	(generator_version "9.0")
	(general
		(thickness 1.6642)
		(legacy_teardrops no)
	)
	(paper "A3")
	(title_block
		(title "PolarFire SoM")
		(date "2025-07-22")
		(rev "1.1.4")
		(company "Antmicro Ltd")
		(comment 1 "www.antmicro.com")
		(comment 9 "footprints 83-84 of 470")
	)
	(layers
		(0 "F.Cu" mixed)
		(4 "In1.Cu" power)
		(6 "In2.Cu" signal)
		(8 "In3.Cu" power)
		(10 "In4.Cu" signal)
		(12 "In5.Cu" power)
		(14 "In6.Cu" power)
		(16 "In7.Cu" signal)
		(18 "In8.Cu" power)
		(20 "In9.Cu" signal)
		(22 "In10.Cu" power)
		(24 "In11.Cu" signal)
		(26 "In12.Cu" signal)
		(2 "B.Cu" mixed)
		(9 "F.Adhes" user "F.Adhesive")
		(11 "B.Adhes" user "B.Adhesive")
		(13 "F.Paste" user)
		(15 "B.Paste" user)
		(5 "F.SilkS" user "F.Silkscreen")
		(7 "B.SilkS" user "B.Silkscreen")
		(1 "F.Mask" user)
		(3 "B.Mask" user)
		(17 "Dwgs.User" user "User.Drawings")
		(19 "Cmts.User" user "User.Comments")
		(21 "Eco1.User" user "User.Eco1")
		(23 "Eco2.User" user "User.Eco2")
		(25 "Edge.Cuts" user)
		(27 "Margin" user)
		(31 "F.CrtYd" user "F.Courtyard")
		(29 "B.CrtYd" user "B.Courtyard")
		(35 "F.Fab" user)
		(33 "B.Fab" user)
	)
	(footprint "antmicro-footprints:R_Array_4x0201_Panasonic_EXB18V"
		(layer "F.Cu")
		(at 201.84884 121.25 -90)
		(property "Reference" "R26"
			(at 1.75 1.11884 180)
			(layer "F.SilkS")
			(effects
				(font
					(size 0.7 0.7)
					(thickness 0.15)
				)
				(justify left bottom)
			)
		)
		(property "Value" "R_4x0R_0201_array"
			(at -1.1 1.8 90)
			(layer "F.Fab")
			(hide yes)
			(effects
				(font
					(size 0.7 0.7)
					(thickness 0.15)
				)
				(justify right bottom)
			)
		)
		(property "Datasheet" "http://industrial.panasonic.com/cdbs/www-data/pdf/AOC0000/AOC0000C14.pdf"
			(at 0 0 270)
			(layer "F.Fab")
			(hide yes)
			(effects
				(font
					(size 1.27 1.27)
					(thickness 0.15)
				)
			)
		)
		(property "Description" "Zero Ohm Network Resistor, Jumper, 0201 [0603 Metric], Thick Film, Isolated, Flat, 4 Resistors"
			(at 0 0 270)
			(layer "F.Fab")
			(hide yes)
			(effects
				(font
					(size 1.27 1.27)
					(thickness 0.15)
				)
			)
		)
		(property "Author" "Antmicro"
			(at 80.59884 323.09884 0)
			(layer "F.Fab")
			(hide yes)
			(effects
				(font
					(size 1 1)
					(thickness 0.15)
				)
			)
		)
		(property "DNP" "DNP"
			(at 80.59884 323.09884 0)
			(layer "F.Fab")
			(hide yes)
			(effects
				(font
					(size 1 1)
					(thickness 0.15)
				)
			)
		)
		(property "License" "Apache-2.0"
			(at 80.59884 323.09884 0)
			(layer "F.Fab")
			(hide yes)
			(effects
				(font
					(size 1 1)
					(thickness 0.15)
				)
			)
		)
		(property "MPN" "EXB-18VR000X"
			(at 80.59884 323.09884 0)
			(layer "F.Fab")
			(hide yes)
			(effects
				(font
					(size 1 1)
					(thickness 0.15)
				)
			)
		)
		(property "Manufacturer" "Panasonic"
			(at 80.59884 323.09884 0)
			(layer "F.Fab")
			(hide yes)
			(effects
				(font
					(size 1 1)
					(thickness 0.15)
				)
			)
		)
		(property "Val" "4x0R_0201"
			(at 80.59884 323.09884 0)
			(layer "F.Fab")
			(hide yes)
			(effects
				(font
					(size 1 1)
					(thickness 0.15)
				)
			)
		)
		(sheetname "/FPGA MSSIO/")
		(sheetfile "fpga-mssio.kicad_sch")
		(attr smd dnp)
		(fp_line
			(start -0.8 -0.45)
			(end -0.8 0.45)
			(stroke
				(width 0.12)
				(type solid)
			)
			(layer "F.SilkS")
		)
		(fp_line
			(start 0.8 -0.45)
			(end 0.8 0.45)
			(stroke
				(width 0.12)
				(type solid)
			)
			(layer "F.SilkS")
		)
		(fp_rect
			(start -0.898 -0.66)
			(end 0.898 0.65)
			(stroke
				(width 0.05)
				(type solid)
			)
			(fill no)
			(layer "F.CrtYd")
		)
		(fp_text user "License: Apache-2.0"
			(at -1.051 6 270)
			(layer "F.Fab")
			(effects
				(font
					(size 0.7 0.7)
					(thickness 0.15)
				)
				(justify left bottom)
			)
		)
		(fp_text user "Author: Antmicro"
			(at -1.051 4.599 270)
			(layer "F.Fab")
			(effects
				(font
					(size 0.7 0.7)
					(thickness 0.15)
				)
				(justify left bottom)
			)
		)
		(fp_text user "${REFERENCE}"
			(at -1.051 3.2 270)
			(layer "F.Fab")
			(effects
				(font
					(size 0.7 0.7)
					(thickness 0.15)
				)
				(justify left bottom)
			)
		)
		(pad "1" smd roundrect
			(at -0.6 0.298 270)
			(size 0.2 0.4)
			(layers "F.Cu" "F.Mask" "F.Paste")
			(roundrect_rratio 0.25)
			(net 273 "/FPGA MSSIO/SD.DAT1")
			(pinfunction "R1.1")
			(pintype "passive")
		)
		(pad "2" smd roundrect
			(at -0.202 0.298 270)
			(size 0.2 0.4)
			(layers "F.Cu" "F.Mask" "F.Paste")
			(roundrect_rratio 0.25)
			(net 274 "/FPGA MSSIO/SD.DAT2")
			(pinfunction "R2.1")
			(pintype "passive")
		)
		(pad "3" smd roundrect
			(at 0.2 0.298 270)
			(size 0.2 0.4)
			(layers "F.Cu" "F.Mask" "F.Paste")
			(roundrect_rratio 0.25)
			(net 276 "/FPGA MSSIO/SD.DAT6")
			(pinfunction "R3.1")
			(pintype "passive")
		)
		(pad "4" smd roundrect
			(at 0.598 0.298 270)
			(size 0.2 0.4)
			(layers "F.Cu" "F.Mask" "F.Paste")
			(roundrect_rratio 0.25)
			(net 277 "/FPGA MSSIO/SD.DAT4")
			(pinfunction "R4.1")
			(pintype "passive")
		)
		(pad "5" smd roundrect
			(at 0.598 -0.3 270)
			(size 0.2 0.4)
			(layers "F.Cu" "F.Mask" "F.Paste")
			(roundrect_rratio 0.25)
			(net 251 "/FPGA MSSIO/MEM.DAT4")
			(pinfunction "R4.2")
			(pintype "passive")
		)
		(pad "6" smd roundrect
			(at 0.2 -0.3 270)
			(size 0.2 0.4)
			(layers "F.Cu" "F.Mask" "F.Paste")
			(roundrect_rratio 0.25)
			(net 252 "/FPGA MSSIO/MEM.DAT6")
			(pinfunction "R3.2")
			(pintype "passive")
		)
		(pad "7" smd roundrect
			(at -0.202 -0.3 270)
			(size 0.2 0.4)
			(layers "F.Cu" "F.Mask" "F.Paste")
			(roundrect_rratio 0.25)
			(net 261 "/FPGA MSSIO/MEM.DAT2")
			(pinfunction "R2.2")
			(pintype "passive")
		)
		(pad "8" smd roundrect
			(at -0.6 -0.3 270)
			(size 0.2 0.4)
			(layers "F.Cu" "F.Mask" "F.Paste")
			(roundrect_rratio 0.25)
			(net 262 "/FPGA MSSIO/MEM.DAT1")
			(pinfunction "R1.2")
			(pintype "passive")
		)
	)
	(footprint "antmicro-footprints:MPS_QFN-14_MP8869S"
		(layer "F.Cu")
		(at 182.858904 150.129531 180)
		(property "Reference" "U8"
			(at -1.861096 2.439531 0)
			(layer "F.SilkS")
			(effects
				(font
					(size 0.7 0.7)
					(thickness 0.15)
				)
				(justify right bottom)
			)
		)
		(property "Value" "MP8869S"
			(at -5.5 3.43 0)
			(layer "F.Fab")
			(hide yes)
			(effects
				(font
					(size 0.7 0.7)
					(thickness 0.15)
				)
				(justify right bottom)
			)
		)
		(property "Datasheet" "https://www.mouser.com/datasheet/2/277/MP8869S-2946178.pdf"
			(at 0 0 180)
			(layer "F.Fab")
			(hide yes)
			(effects
				(font
					(size 1.27 1.27)
					(thickness 0.15)
				)
			)
		)
		(property "Description" "DC-DC Switching Synchronous Buck Regulator, 2.85V-18V in, 600mV to 5.5V out, 12A, 500kHz, QFN-14"
			(at 0 0 180)
			(layer "F.Fab")
			(hide yes)
			(effects
				(font
					(size 1.27 1.27)
					(thickness 0.15)
				)
			)
		)
		(property "Author" "Antmicro"
			(at 365.717808 300.259062 0)
			(layer "F.Fab")
			(hide yes)
			(effects
				(font
					(size 1 1)
					(thickness 0.15)
				)
			)
		)
		(property "License" "Apache-2.0"
			(at 365.717808 300.259062 0)
			(layer "F.Fab")
			(hide yes)
			(effects
				(font
					(size 1 1)
					(thickness 0.15)
				)
			)
		)
		(property "MPN" "MP8869SGL-P"
			(at 365.717808 300.259062 0)
			(layer "F.Fab")
			(hide yes)
			(effects
				(font
					(size 1 1)
					(thickness 0.15)
				)
			)
		)
		(property "Manufacturer" "Monolithic Power Systems"
			(at 365.717808 300.259062 0)
			(layer "F.Fab")
			(hide yes)
			(effects
				(font
					(size 1 1)
					(thickness 0.15)
				)
			)
		)
		(property ki_fp_filters "QFN-14_MP8869S_MNP")
		(sheetname "/Supply/")
		(sheetfile "supply.kicad_sch")
		(attr smd)
		(fp_line
			(start 1.675 0.981)
			(end 1.675 2.171)
			(stroke
				(width 0.15)
				(type solid)
			)
			(layer "F.SilkS")
		)
		(fp_line
			(start 1.675 -2.173)
			(end 1.675 -0.983)
			(stroke
				(width 0.15)
				(type solid)
			)
			(layer "F.SilkS")
		)
		(fp_line
			(start -1.678 2.171)
			(end -1.678 0.481)
			(stroke
				(width 0.15)
				(type solid)
			)
			(layer "F.SilkS")
		)
		(fp_line
			(start -1.678 -0.959)
			(end -1.678 -2.173)
			(stroke
				(width 0.15)
				(type solid)
			)
			(layer "F.SilkS")
		)
		(fp_circle
			(center -2.361 -0.5)
			(end -2.311 -0.5)
			(stroke
				(width 0.15)
				(type solid)
			)
			(fill yes)
			(layer "F.SilkS")
		)
		(fp_rect
			(start -2.061 -2.55)
			(end 2.06 2.548)
			(stroke
				(width 0.05)
				(type solid)
			)
			(fill no)
			(layer "F.CrtYd")
		)
		(fp_line
			(start 1.548 2.043)
			(end 1.548 -2.045)
			(stroke
				(width 0.15)
				(type solid)
			)
			(layer "F.Fab")
		)
		(fp_line
			(start 1.548 -2.045)
			(end -1.551 -2.045)
			(stroke
				(width 0.15)
				(type solid)
			)
			(layer "F.Fab")
		)
		(fp_line
			(start -1.541 -1.841)
			(end -1.341 -2.04)
			(stroke
				(width 0.15)
				(type solid)
			)
			(layer "F.Fab")
		)
		(fp_line
			(start -1.551 2.043)
			(end 1.548 2.043)
			(stroke
				(width 0.15)
				(type solid)
			)
			(layer "F.Fab")
		)
		(fp_line
			(start -1.551 -2.045)
			(end -1.551 2.043)
			(stroke
				(width 0.15)
				(type solid)
			)
			(layer "F.Fab")
		)
		(fp_text user "License: Apache-2.0"
			(at -5.5 5.43 180)
			(layer "F.Fab")
			(effects
				(font
					(size 0.7 0.7)
					(thickness 0.15)
				)
				(justify left bottom)
			)
		)
		(fp_text user "${REFERENCE}"
			(at -5.5 6.63 180)
			(layer "F.Fab")
			(effects
				(font
					(size 0.7 0.7)
					(thickness 0.15)
				)
				(justify left bottom)
			)
		)
		(fp_text user "Author: Antmicro"
			(at -5.5 7.83 180)
			(layer "F.Fab")
			(effects
				(font
					(size 0.7 0.7)
					(thickness 0.15)
				)
				(justify left bottom)
			)
		)
		(pad "1" smd custom
			(at -1.401 -0.5 180)
			(size 0.799998 0.249998)
			(layers "F.Cu" "F.Mask" "F.Paste")
			(net 149 "/Supply/1V05_BS")
			(pinfunction "BST")
			(pintype "unspecified")
			(options
				(clearance outline)
				(anchor rect)
			)
			(primitives
				(gr_poly
					(pts
						(xy -0.400002 -0.125001) (xy -0.400002 0.124999) (xy 0.499998 0.124999) (xy 0.499998 -0.000001)
						(xy 0.374998 -0.125001)
					)
					(width 0.1)
					(fill yes)
				)
			)
		)
		(pad "2" smd rect
			(at -0.851 0 180)
			(size 1.9 0.3)
			(layers "F.Cu" "F.Mask" "F.Paste")
			(net 150 "/Supply/1V05_SW")
			(pinfunction "SW")
			(pintype "output")
		)
		(pad "3" smd rect
			(at -1.002 1.848 270)
			(size 0.9 0.25)
			(layers "F.Cu" "F.Mask" "F.Paste")
			(net 92 "/FPGA MSSIO/SUPPLY.SCL")
			(pinfunction "SCL")
			(pintype "unspecified")
		)
		(pad "4" smd rect
			(at -0.5 1.848 270)
			(size 0.9 0.25)
			(layers "F.Cu" "F.Mask" "F.Paste")
			(net 100 "/FPGA MSSIO/SUPPLY.SDA")
			(pinfunction "SDA")
			(pintype "unspecified")
		)
		(pad "5" smd rect
			(at 0 1.848 270)
			(size 0.9 0.25)
			(layers "F.Cu" "F.Mask" "F.Paste")
			(net 187 "/Supply/PWRON")
			(pinfunction "EN")
			(pintype "unspecified")
		)
		(pad "6" smd rect
			(at 0.498 1.848 270)
			(size 0.9 0.25)
			(layers "F.Cu" "F.Mask" "F.Paste")
			(net 417 "GND")
			(pinfunction "A0")
			(pintype "unspecified")
		)
		(pad "7" smd rect
			(at 0.999 1.848 270)
			(size 0.9 0.25)
			(layers "F.Cu" "F.Mask" "F.Paste")
			(net 656 "/Supply/PG")
			(pinfunction "PG")
			(pintype "unspecified")
		)
		(pad "8" smd custom
			(at 0.849 0.498 180)
			(size 0.127 0.127)
			(layers "F.Cu" "F.Mask" "F.Paste")
			(net 417 "GND")
			(pinfunction "PGND")
			(pintype "power_in")
			(options
				(clearance outline)
				(anchor rect)
			)
			(primitives
				(gr_poly
					(pts
						(xy 0.95 0.15) (xy 0.95 -0.15) (xy -0.55 -0.15) (xy -0.65 -0.05) (xy -0.95 -0.05) (xy -0.95 0.15)
					)
					(width 0.1)
					(fill yes)
				)
			)
		)
		(pad "9" smd custom
			(at 0.849 -0.5 180)
			(size 0.127 0.127)
			(layers "F.Cu" "F.Mask" "F.Paste")
			(net 90 "+5V")
			(pinfunction "VIN")
			(pintype "power_in")
			(options
				(clearance outline)
				(anchor rect)
			)
			(primitives
				(gr_poly
					(pts
						(xy 0.95 -0.15) (xy 0.95 0.15) (xy -0.55 0.15) (xy -0.65 0.05) (xy -0.95 0.05) (xy -0.95 -0.15)
					)
					(width 0.1)
					(fill yes)
				)
			)
		)
		(pad "10" smd rect
			(at 0.999 -1.851 270)
			(size 0.9 0.25)
			(layers "F.Cu" "F.Mask" "F.Paste")
			(net 522 "/Supply/1V05_REG")
			(pinfunction "VOUT")
			(pintype "unspecified")
		)
		(pad "11" smd rect
			(at 0.498 -1.851 270)
			(size 0.9 0.25)
			(layers "F.Cu" "F.Mask" "F.Paste")
			(net 398 "/Supply/1V05_FB")
			(pinfunction "FB")
			(pintype "unspecified")
		)
		(pad "12" smd rect
			(at 0 -1.851 270)
			(size 0.9 0.25)
			(layers "F.Cu" "F.Mask" "F.Paste")
			(net 228 "/Supply/1V05_SS")
			(pinfunction "SS")
			(pintype "unspecified")
		)
		(pad "13" smd rect
			(at -0.5 -1.851 270)
			(size 0.9 0.25)
			(layers "F.Cu" "F.Mask" "F.Paste")
			(net 148 "/Supply/1V05_VCC")
			(pinfunction "VCC")
			(pintype "power_out")
		)
		(pad "14" smd rect
			(at -1.002 -1.851 270)
			(size 0.9 0.25)
			(layers "F.Cu" "F.Mask" "F.Paste")
			(net 417 "GND")
			(pinfunction "AGND")
			(pintype "power_in")
		)
	)
)
